(kicad_pcb
	(version 20260206)
	(generator "pcbnew")
	(generator_version "10.0")
	(general
		(thickness 1.6)
		(legacy_teardrops no)
	)
	(paper "A4")
	(title_block
		(title "01162023_DA0F0TEBIF0_F0T_Expander_BD_F_brd_V02_OCP.brd")
		(comment 1 "Grand Teton / footprints 7317-7324 of 9728")
	)
	(layers
		(0 "F.Cu" signal "TOP")
		(4 "In1.Cu" signal "GND")
		(6 "In2.Cu" signal "VCC")
		(8 "In3.Cu" signal "VCC1")
		(10 "In4.Cu" signal "GND1")
		(12 "In5.Cu" signal "IN1")
		(14 "In6.Cu" signal "GND2")
		(16 "In7.Cu" signal "IN2")
		(18 "In8.Cu" signal "GND3")
		(20 "In9.Cu" signal "IN3")
		(22 "In10.Cu" signal "GND4")
		(24 "In11.Cu" signal "IN4")
		(26 "In12.Cu" signal "GND5")
		(28 "In13.Cu" signal "IN5")
		(30 "In14.Cu" signal "GND6")
		(32 "In15.Cu" signal "IN6")
		(34 "In16.Cu" signal "GND7")
		(2 "B.Cu" signal "BOTTOM")
		(9 "F.Adhes" user "F.Adhesive")
		(11 "B.Adhes" user "B.Adhesive")
		(13 "F.Paste" user "Package Geometry/Pastemask Top")
		(15 "B.Paste" user "Package Geometry/Pastemask Bottom")
		(5 "F.SilkS" user "Ref Des/Silkscreen Top")
		(7 "B.SilkS" user "Ref Des/Silkscreen Bottom")
		(1 "F.Mask" user "Board Geometry/Soldermask Top")
		(3 "B.Mask" user "Board Geometry/Soldermask Bottom")
		(17 "Dwgs.User" user "User.Drawings")
		(19 "Cmts.User" user "User.Comments")
		(21 "Eco1.User" user "User.Eco1")
		(23 "Eco2.User" user "User.Eco2")
		(25 "Edge.Cuts" user "Board Geometry/Outline")
		(27 "Margin" user)
		(31 "F.CrtYd" user "Package Geometry/Place Bound Top")
		(29 "B.CrtYd" user "Package Geometry/Place Bound Bottom")
		(35 "F.Fab" user "Ref Des/Assembly Top")
		(33 "B.Fab" user "Ref Des/Assembly Bottom")
	)
	(footprint ""
		(layer "B.Cu")
		(at 358.22001 -252.186694 180)
		(property "Reference" "R6716"
			(at 0 0 0)
			(layer "B.SilkS")
			(hide yes)
			(effects
				(font
					(size 1.27 1.27)
				)
				(justify mirror)
			)
		)
		(property "Value" ""
			(at 0 0 0)
			(layer "B.Fab")
			(effects
				(font
					(size 1.27 1.27)
				)
				(justify mirror)
			)
		)
		(duplicate_pad_numbers_are_jumpers no)
		(fp_line
			(start 0.7874 0.4064)
			(end 0.7874 -0.4064)
			(stroke
				(width 0.1524)
				(type default)
			)
			(layer "B.SilkS")
		)
		(fp_line
			(start 0.7874 -0.4064)
			(end -0.7874 -0.4064)
			(stroke
				(width 0.1524)
				(type default)
			)
			(layer "B.SilkS")
		)
		(fp_line
			(start -0.7874 0.4064)
			(end 0.7874 0.4064)
			(stroke
				(width 0.1524)
				(type default)
			)
			(layer "B.SilkS")
		)
		(fp_line
			(start -0.7874 -0.4064)
			(end -0.7874 0.4064)
			(stroke
				(width 0.1524)
				(type default)
			)
			(layer "B.SilkS")
		)
		(fp_line
			(start 0.67945 0.3048)
			(end 0.67945 -0.305054)
			(stroke
				(width 0.1)
				(type default)
			)
			(layer "B.Fab")
		)
		(fp_line
			(start 0.67945 -0.305054)
			(end 0.12065 -0.305054)
			(stroke
				(width 0.1)
				(type default)
			)
			(layer "B.Fab")
		)
		(fp_line
			(start 0.12065 0.3048)
			(end 0.67945 0.3048)
			(stroke
				(width 0.1)
				(type default)
			)
			(layer "B.Fab")
		)
		(fp_line
			(start 0.12065 0.2794)
			(end 0.12065 0.3048)
			(stroke
				(width 0.1)
				(type default)
			)
			(layer "B.Fab")
		)
		(fp_line
			(start 0.12065 -0.2794)
			(end -0.12065 -0.2794)
			(stroke
				(width 0.1)
				(type default)
			)
			(layer "B.Fab")
		)
		(fp_line
			(start 0.12065 -0.305054)
			(end 0.12065 -0.2794)
			(stroke
				(width 0.1)
				(type default)
			)
			(layer "B.Fab")
		)
		(fp_line
			(start -0.120396 0.3048)
			(end -0.120396 0.2794)
			(stroke
				(width 0.1)
				(type default)
			)
			(layer "B.Fab")
		)
		(fp_line
			(start -0.120396 0.2794)
			(end 0.12065 0.2794)
			(stroke
				(width 0.1)
				(type default)
			)
			(layer "B.Fab")
		)
		(fp_line
			(start -0.12065 -0.2794)
			(end -0.12065 -0.3048)
			(stroke
				(width 0.1)
				(type default)
			)
			(layer "B.Fab")
		)
		(fp_line
			(start -0.12065 -0.3048)
			(end -0.67945 -0.3048)
			(stroke
				(width 0.1)
				(type default)
			)
			(layer "B.Fab")
		)
		(fp_line
			(start -0.67945 0.3048)
			(end -0.120396 0.3048)
			(stroke
				(width 0.1)
				(type default)
			)
			(layer "B.Fab")
		)
		(fp_line
			(start -0.67945 -0.3048)
			(end -0.67945 0.3048)
			(stroke
				(width 0.1)
				(type default)
			)
			(layer "B.Fab")
		)
		(pad "1" smd circle
			(at 0.40005 0)
			(size 0 0)
			(layers "B.Cu" "B.Mask" "B.Paste")
			(net "SMB_SML1_PMBUS_HSC_SCL")
		)
		(pad "2" smd circle
			(at -0.40005 0)
			(size 0 0)
			(layers "B.Cu" "B.Mask" "B.Paste")
			(net "SMB_BIC_I2C6_MUX_VR_R_SCL")
		)
	)
	(footprint ""
		(layer "B.Cu")
		(at 279.974802 -298.00804 90)
		(property "Reference" "C3417"
			(at 0 0 90)
			(layer "B.SilkS")
			(hide yes)
			(effects
				(font
					(size 1.27 1.27)
				)
				(justify mirror)
			)
		)
		(property "Value" ""
			(at 0 0 90)
			(layer "B.Fab")
			(effects
				(font
					(size 1.27 1.27)
				)
				(justify mirror)
			)
		)
		(duplicate_pad_numbers_are_jumpers no)
		(fp_line
			(start 0.299974 -0.150114)
			(end -0.299974 -0.150114)
			(stroke
				(width 0.1)
				(type default)
			)
			(layer "B.Fab")
		)
		(fp_line
			(start -0.299974 -0.150114)
			(end -0.299974 0.150114)
			(stroke
				(width 0.1)
				(type default)
			)
			(layer "B.Fab")
		)
		(fp_line
			(start 0.299974 0.150114)
			(end 0.299974 -0.150114)
			(stroke
				(width 0.1)
				(type default)
			)
			(layer "B.Fab")
		)
		(fp_line
			(start -0.299974 0.150114)
			(end 0.299974 0.150114)
			(stroke
				(width 0.1)
				(type default)
			)
			(layer "B.Fab")
		)
		(pad "1" smd rect
			(at 0.2667 0 270)
			(size 0.3048 0.381)
			(layers "B.Cu" "B.Mask" "B.Paste")
			(net "SYSPLL_VDDA18_PEX2")
		)
		(pad "2" smd rect
			(at -0.2667 0 270)
			(size 0.3048 0.381)
			(layers "B.Cu" "B.Mask" "B.Paste")
			(net "GND")
		)
	)
	(footprint ""
		(layer "B.Cu")
		(at 354.889562 -313.620404)
		(property "Reference" "L76"
			(at 0 0 0)
			(layer "B.SilkS")
			(hide yes)
			(effects
				(font
					(size 1.27 1.27)
				)
				(justify mirror)
			)
		)
		(property "Value" ""
			(at 0 0 0)
			(layer "B.Fab")
			(effects
				(font
					(size 1.27 1.27)
				)
				(justify mirror)
			)
		)
		(duplicate_pad_numbers_are_jumpers no)
		(fp_line
			(start -2.248154 -4.9911)
			(end 2.248154 -4.9911)
			(stroke
				(width 0.1524)
				(type default)
			)
			(layer "B.SilkS")
		)
		(fp_line
			(start -2.248154 -1.954276)
			(end -2.248154 -4.9911)
			(stroke
				(width 0.1524)
				(type default)
			)
			(layer "B.SilkS")
		)
		(fp_line
			(start -2.248154 4.9911)
			(end -2.248154 1.986534)
			(stroke
				(width 0.1524)
				(type default)
			)
			(layer "B.SilkS")
		)
		(fp_line
			(start 2.248154 -4.9911)
			(end 2.248154 -1.954276)
			(stroke
				(width 0.1524)
				(type default)
			)
			(layer "B.SilkS")
		)
		(fp_line
			(start 2.248154 1.986534)
			(end 2.248154 4.9911)
			(stroke
				(width 0.1524)
				(type default)
			)
			(layer "B.SilkS")
		)
		(fp_line
			(start 2.248154 4.9911)
			(end -2.248154 4.9911)
			(stroke
				(width 0.1524)
				(type default)
			)
			(layer "B.SilkS")
		)
		(fp_line
			(start -1.700022 -0.899922)
			(end 1.700022 -0.899922)
			(stroke
				(width 0.1)
				(type default)
			)
			(layer "B.Fab")
		)
		(fp_line
			(start -1.700022 0.899922)
			(end -1.700022 -0.899922)
			(stroke
				(width 0.1)
				(type default)
			)
			(layer "B.Fab")
		)
		(fp_line
			(start 1.700022 -0.899922)
			(end 1.700022 0.899922)
			(stroke
				(width 0.1)
				(type default)
			)
			(layer "B.Fab")
		)
		(fp_line
			(start 1.700022 0.899922)
			(end -1.700022 0.899922)
			(stroke
				(width 0.1)
				(type default)
			)
			(layer "B.Fab")
		)
		(pad "1" smd rect
			(at 1.575054 0 180)
			(size 1.1684 9.8044)
			(layers "B.Cu" "B.Mask" "B.Paste")
			(net "P0V8_PEX3")
		)
		(pad "2" smd rect
			(at -1.575054 0 180)
			(size 1.1684 9.8044)
			(layers "B.Cu" "B.Mask" "B.Paste")
			(net "P0V8_SERDES_VDDA_PEX3")
		)
	)
	(footprint ""
		(layer "B.Cu")
		(at 125.704854 -321.813174 -90)
		(property "Reference" "R6475"
			(at 0 0 90)
			(layer "B.SilkS")
			(hide yes)
			(effects
				(font
					(size 1.27 1.27)
				)
				(justify mirror)
			)
		)
		(property "Value" ""
			(at 0 0 90)
			(layer "B.Fab")
			(effects
				(font
					(size 1.27 1.27)
				)
				(justify mirror)
			)
		)
		(duplicate_pad_numbers_are_jumpers no)
		(fp_line
			(start -0.7874 0.4064)
			(end 0.7874 0.4064)
			(stroke
				(width 0.1524)
				(type default)
			)
			(layer "B.SilkS")
		)
		(fp_line
			(start 0.7874 0.4064)
			(end 0.7874 -0.4064)
			(stroke
				(width 0.1524)
				(type default)
			)
			(layer "B.SilkS")
		)
		(fp_line
			(start -0.7874 -0.4064)
			(end -0.7874 0.4064)
			(stroke
				(width 0.1524)
				(type default)
			)
			(layer "B.SilkS")
		)
		(fp_line
			(start 0.7874 -0.4064)
			(end -0.7874 -0.4064)
			(stroke
				(width 0.1524)
				(type default)
			)
			(layer "B.SilkS")
		)
		(fp_line
			(start -0.67945 0.3048)
			(end -0.120396 0.3048)
			(stroke
				(width 0.1)
				(type default)
			)
			(layer "B.Fab")
		)
		(fp_line
			(start -0.120396 0.3048)
			(end -0.120396 0.2794)
			(stroke
				(width 0.1)
				(type default)
			)
			(layer "B.Fab")
		)
		(fp_line
			(start 0.12065 0.3048)
			(end 0.67945 0.3048)
			(stroke
				(width 0.1)
				(type default)
			)
			(layer "B.Fab")
		)
		(fp_line
			(start 0.67945 0.3048)
			(end 0.67945 -0.305054)
			(stroke
				(width 0.1)
				(type default)
			)
			(layer "B.Fab")
		)
		(fp_line
			(start -0.120396 0.2794)
			(end 0.12065 0.2794)
			(stroke
				(width 0.1)
				(type default)
			)
			(layer "B.Fab")
		)
		(fp_line
			(start 0.12065 0.2794)
			(end 0.12065 0.3048)
			(stroke
				(width 0.1)
				(type default)
			)
			(layer "B.Fab")
		)
		(fp_line
			(start -0.12065 -0.2794)
			(end -0.12065 -0.3048)
			(stroke
				(width 0.1)
				(type default)
			)
			(layer "B.Fab")
		)
		(fp_line
			(start 0.12065 -0.2794)
			(end -0.12065 -0.2794)
			(stroke
				(width 0.1)
				(type default)
			)
			(layer "B.Fab")
		)
		(fp_line
			(start -0.67945 -0.3048)
			(end -0.67945 0.3048)
			(stroke
				(width 0.1)
				(type default)
			)
			(layer "B.Fab")
		)
		(fp_line
			(start -0.12065 -0.3048)
			(end -0.67945 -0.3048)
			(stroke
				(width 0.1)
				(type default)
			)
			(layer "B.Fab")
		)
		(fp_line
			(start 0.12065 -0.305054)
			(end 0.12065 -0.2794)
			(stroke
				(width 0.1)
				(type default)
			)
			(layer "B.Fab")
		)
		(fp_line
			(start 0.67945 -0.305054)
			(end 0.12065 -0.305054)
			(stroke
				(width 0.1)
				(type default)
			)
			(layer "B.Fab")
		)
		(pad "1" smd circle
			(at 0.40005 0 90)
			(size 0 0)
			(layers "B.Cu" "B.Mask" "B.Paste")
			(net "P0V8_SERDES_VDDA_PEX1")
		)
		(pad "2" smd circle
			(at -0.40005 0 90)
			(size 0 0)
			(layers "B.Cu" "B.Mask" "B.Paste")
			(net "P0V8_SERDES_VDDA_PEX1_C0")
		)
	)
	(footprint ""
		(layer "B.Cu")
		(at 189.049914 -297.79976 180)
		(property "Reference" "C3123"
			(at 0 0 0)
			(layer "B.SilkS")
			(hide yes)
			(effects
				(font
					(size 1.27 1.27)
				)
				(justify mirror)
			)
		)
		(property "Value" ""
			(at 0 0 0)
			(layer "B.Fab")
			(effects
				(font
					(size 1.27 1.27)
				)
				(justify mirror)
			)
		)
		(duplicate_pad_numbers_are_jumpers no)
		(fp_line
			(start 0.299974 0.150114)
			(end 0.299974 -0.150114)
			(stroke
				(width 0.1)
				(type default)
			)
			(layer "B.Fab")
		)
		(fp_line
			(start 0.299974 -0.150114)
			(end -0.299974 -0.150114)
			(stroke
				(width 0.1)
				(type default)
			)
			(layer "B.Fab")
		)
		(fp_line
			(start -0.299974 0.150114)
			(end 0.299974 0.150114)
			(stroke
				(width 0.1)
				(type default)
			)
			(layer "B.Fab")
		)
		(fp_line
			(start -0.299974 -0.150114)
			(end -0.299974 0.150114)
			(stroke
				(width 0.1)
				(type default)
			)
			(layer "B.Fab")
		)
		(pad "1" smd rect
			(at 0.2667 0)
			(size 0.3048 0.381)
			(layers "B.Cu" "B.Mask" "B.Paste")
			(net "P1V25_SERDES_VDDPLL_PEX1")
		)
		(pad "2" smd rect
			(at -0.2667 0)
			(size 0.3048 0.381)
			(layers "B.Cu" "B.Mask" "B.Paste")
			(net "GND")
		)
	)
	(footprint ""
		(layer "B.Cu")
		(at 74.026776 -301.124874 -90)
		(property "Reference" "R1244"
			(at 0 0 90)
			(layer "B.SilkS")
			(hide yes)
			(effects
				(font
					(size 1.27 1.27)
				)
				(justify mirror)
			)
		)
		(property "Value" ""
			(at 0 0 90)
			(layer "B.Fab")
			(effects
				(font
					(size 1.27 1.27)
				)
				(justify mirror)
			)
		)
		(duplicate_pad_numbers_are_jumpers no)
		(fp_line
			(start -0.7874 0.4064)
			(end 0.7874 0.4064)
			(stroke
				(width 0.1524)
				(type default)
			)
			(layer "B.SilkS")
		)
		(fp_line
			(start 0.7874 0.4064)
			(end 0.7874 -0.4064)
			(stroke
				(width 0.1524)
				(type default)
			)
			(layer "B.SilkS")
		)
		(fp_line
			(start -0.7874 -0.4064)
			(end -0.7874 0.4064)
			(stroke
				(width 0.1524)
				(type default)
			)
			(layer "B.SilkS")
		)
		(fp_line
			(start 0.7874 -0.4064)
			(end -0.7874 -0.4064)
			(stroke
				(width 0.1524)
				(type default)
			)
			(layer "B.SilkS")
		)
		(fp_line
			(start -0.67945 0.3048)
			(end -0.120396 0.3048)
			(stroke
				(width 0.1)
				(type default)
			)
			(layer "B.Fab")
		)
		(fp_line
			(start -0.120396 0.3048)
			(end -0.120396 0.2794)
			(stroke
				(width 0.1)
				(type default)
			)
			(layer "B.Fab")
		)
		(fp_line
			(start 0.12065 0.3048)
			(end 0.67945 0.3048)
			(stroke
				(width 0.1)
				(type default)
			)
			(layer "B.Fab")
		)
		(fp_line
			(start 0.67945 0.3048)
			(end 0.67945 -0.305054)
			(stroke
				(width 0.1)
				(type default)
			)
			(layer "B.Fab")
		)
		(fp_line
			(start -0.120396 0.2794)
			(end 0.12065 0.2794)
			(stroke
				(width 0.1)
				(type default)
			)
			(layer "B.Fab")
		)
		(fp_line
			(start 0.12065 0.2794)
			(end 0.12065 0.3048)
			(stroke
				(width 0.1)
				(type default)
			)
			(layer "B.Fab")
		)
		(fp_line
			(start -0.12065 -0.2794)
			(end -0.12065 -0.3048)
			(stroke
				(width 0.1)
				(type default)
			)
			(layer "B.Fab")
		)
		(fp_line
			(start 0.12065 -0.2794)
			(end -0.12065 -0.2794)
			(stroke
				(width 0.1)
				(type default)
			)
			(layer "B.Fab")
		)
		(fp_line
			(start -0.67945 -0.3048)
			(end -0.67945 0.3048)
			(stroke
				(width 0.1)
				(type default)
			)
			(layer "B.Fab")
		)
		(fp_line
			(start -0.12065 -0.3048)
			(end -0.67945 -0.3048)
			(stroke
				(width 0.1)
				(type default)
			)
			(layer "B.Fab")
		)
		(fp_line
			(start 0.12065 -0.305054)
			(end 0.12065 -0.2794)
			(stroke
				(width 0.1)
				(type default)
			)
			(layer "B.Fab")
		)
		(fp_line
			(start 0.67945 -0.305054)
			(end 0.12065 -0.305054)
			(stroke
				(width 0.1)
				(type default)
			)
			(layer "B.Fab")
		)
		(pad "1" smd circle
			(at 0.40005 0 90)
			(size 0 0)
			(layers "B.Cu" "B.Mask" "B.Paste")
			(net "PEX0_ADCTEMP_VINP0")
		)
		(pad "2" smd circle
			(at -0.40005 0 90)
			(size 0 0)
			(layers "B.Cu" "B.Mask" "B.Paste")
			(net "GND")
		)
	)
	(footprint ""
		(layer "B.Cu")
		(at 292.351206 -305.399948 -90)
		(property "Reference" "C3315"
			(at 0 0 90)
			(layer "B.SilkS")
			(hide yes)
			(effects
				(font
					(size 1.27 1.27)
				)
				(justify mirror)
			)
		)
		(property "Value" ""
			(at 0 0 90)
			(layer "B.Fab")
			(effects
				(font
					(size 1.27 1.27)
				)
				(justify mirror)
			)
		)
		(duplicate_pad_numbers_are_jumpers no)
		(fp_line
			(start -0.299974 0.150114)
			(end 0.299974 0.150114)
			(stroke
				(width 0.1)
				(type default)
			)
			(layer "B.Fab")
		)
		(fp_line
			(start 0.299974 0.150114)
			(end 0.299974 -0.150114)
			(stroke
				(width 0.1)
				(type default)
			)
			(layer "B.Fab")
		)
		(fp_line
			(start -0.299974 -0.150114)
			(end -0.299974 0.150114)
			(stroke
				(width 0.1)
				(type default)
			)
			(layer "B.Fab")
		)
		(fp_line
			(start 0.299974 -0.150114)
			(end -0.299974 -0.150114)
			(stroke
				(width 0.1)
				(type default)
			)
			(layer "B.Fab")
		)
		(pad "1" smd rect
			(at 0.2667 0 90)
			(size 0.3048 0.381)
			(layers "B.Cu" "B.Mask" "B.Paste")
			(net "P1V25_SERDES_VDDPLL_PEX2")
		)
		(pad "2" smd rect
			(at -0.2667 0 90)
			(size 0.3048 0.381)
			(layers "B.Cu" "B.Mask" "B.Paste")
			(net "GND")
		)
	)
	(footprint ""
		(layer "B.Cu")
		(at 341.975948 -323.15531 -90)
		(property "Reference" "R6509"
			(at 0 0 90)
			(layer "B.SilkS")
			(hide yes)
			(effects
				(font
					(size 1.27 1.27)
				)
				(justify mirror)
			)
		)
		(property "Value" ""
			(at 0 0 90)
			(layer "B.Fab")
			(effects
				(font
					(size 1.27 1.27)
				)
				(justify mirror)
			)
		)
		(duplicate_pad_numbers_are_jumpers no)
		(fp_line
			(start -0.7874 0.4064)
			(end 0.7874 0.4064)
			(stroke
				(width 0.1524)
				(type default)
			)
			(layer "B.SilkS")
		)
		(fp_line
			(start 0.7874 0.4064)
			(end 0.7874 -0.4064)
			(stroke
				(width 0.1524)
				(type default)
			)
			(layer "B.SilkS")
		)
		(fp_line
			(start -0.7874 -0.4064)
			(end -0.7874 0.4064)
			(stroke
				(width 0.1524)
				(type default)
			)
			(layer "B.SilkS")
		)
		(fp_line
			(start 0.7874 -0.4064)
			(end -0.7874 -0.4064)
			(stroke
				(width 0.1524)
				(type default)
			)
			(layer "B.SilkS")
		)
		(fp_line
			(start -0.67945 0.3048)
			(end -0.120396 0.3048)
			(stroke
				(width 0.1)
				(type default)
			)
			(layer "B.Fab")
		)
		(fp_line
			(start -0.120396 0.3048)
			(end -0.120396 0.2794)
			(stroke
				(width 0.1)
				(type default)
			)
			(layer "B.Fab")
		)
		(fp_line
			(start 0.12065 0.3048)
			(end 0.67945 0.3048)
			(stroke
				(width 0.1)
				(type default)
			)
			(layer "B.Fab")
		)
		(fp_line
			(start 0.67945 0.3048)
			(end 0.67945 -0.305054)
			(stroke
				(width 0.1)
				(type default)
			)
			(layer "B.Fab")
		)
		(fp_line
			(start -0.120396 0.2794)
			(end 0.12065 0.2794)
			(stroke
				(width 0.1)
				(type default)
			)
			(layer "B.Fab")
		)
		(fp_line
			(start 0.12065 0.2794)
			(end 0.12065 0.3048)
			(stroke
				(width 0.1)
				(type default)
			)
			(layer "B.Fab")
		)
		(fp_line
			(start -0.12065 -0.2794)
			(end -0.12065 -0.3048)
			(stroke
				(width 0.1)
				(type default)
			)
			(layer "B.Fab")
		)
		(fp_line
			(start 0.12065 -0.2794)
			(end -0.12065 -0.2794)
			(stroke
				(width 0.1)
				(type default)
			)
			(layer "B.Fab")
		)
		(fp_line
			(start -0.67945 -0.3048)
			(end -0.67945 0.3048)
			(stroke
				(width 0.1)
				(type default)
			)
			(layer "B.Fab")
		)
		(fp_line
			(start -0.12065 -0.3048)
			(end -0.67945 -0.3048)
			(stroke
				(width 0.1)
				(type default)
			)
			(layer "B.Fab")
		)
		(fp_line
			(start 0.12065 -0.305054)
			(end 0.12065 -0.2794)
			(stroke
				(width 0.1)
				(type default)
			)
			(layer "B.Fab")
		)
		(fp_line
			(start 0.67945 -0.305054)
			(end 0.12065 -0.305054)
			(stroke
				(width 0.1)
				(type default)
			)
			(layer "B.Fab")
		)
		(pad "1" smd circle
			(at 0.40005 0 90)
			(size 0 0)
			(layers "B.Cu" "B.Mask" "B.Paste")
			(net "P0V8_SERDES_VDDA_PEX2")
		)
		(pad "2" smd circle
			(at -0.40005 0 90)
			(size 0 0)
			(layers "B.Cu" "B.Mask" "B.Paste")
			(net "P0V8_SERDES_VDDA_PEX2_C4")
		)
	)
)
